# S9S_MB_2U (Grand Teton) — schematic netlist excerpt (pin names and nets, part order shuffled) for the footprints in the layout excerpt that follows; sources: Cadence DE-HDL packaged netlist, KiCad conversion of 03242023_DA0F0TMBIJ0_F0T_Motherboard_J_brd_V01_OCP.brd

U13  9SQ440NQQI8  IC  pkg QFN100_TH_0-5_8X8  page 208
  \25mpg\  = FM_CK440Q_DEV_25M_EN
  \25m1#\  = CLK_25M_CK440_CPU1_DN
  \25m1\  = CLK_25M_CK440_CPU1_DP
  \25m0#\  = CLK_25M_CK440_CPU0_DN
  \25m0\  = CLK_25M_CK440_CPU0_DP
  PFT_OUT  = TP_CLK_CK440_PFT_OUT_DP
  \pft_out#\  = TP_CLK_CK440_PFT_OUT_DN
  PFT_IN  = TP_CLK_PFT_IN_DP
  \pft_in#\  = TP_CLK_PFT_IN_DN
  SCLK  = SMB_HOST_CLK_3V3AUX_SCL
  SMB_ADR0_TRI  = CLK_CK440_SMB_ADDR0
  VDDXTAL  = P3V3_AUX_CLK_GEN_VDDXTAL_CK440
  XIN_CLKIN  = XTAL_CLK_GEN1_25M_X1
  GNDXTAL  = GND
  NC_A15  = NC_CK440_A15
  SS_EN_TRI  = FM_CLK_CK440_SS_EN
  \pwrgd||pwrdn#\  = FM_PLD_CLKS_DEV_EN
  \100m6#\  = NC_CLK_CK440_100M6_DN
  \100m6\  = NC_CLK_CK440_100M6_DP
  \100m5#\  = NC_CLK_CK440_100M5_DN
  \100m5\  = NC_CLK_CK440_100M5_DP
  \100m4#\  = NC_CLK_CK440_100M4_DN
  \100m4\  = NC_CLK_CK440_100M4_DP
  \100m3#\  = NC_CLK_CK440_100M3_DN
  \100m3\  = NC_CLK_CK440_100M3_DP
  \oe3#\  = CK440Q_OE_3
  \100m2#\  = NC_CLK_CK440_100M2_DN
  \100m2\  = NC_CLK_CK440_100M2_DP
  \oe2#\  = CK440Q_OE_2
  \oe1#\  = CK440Q_OE_1
  \100m1#\  = NC_CLK_CK440_100M1_DN
  \100m1\  = NC_CLK_CK440_100M1_DP
  \100m0#\  = CLK_100M_DB2000_DN
  \100m0\  = CLK_100M_DB2000_DP
  \mxck8#\  = NC_CLK_CK440_MXCK8_DN
  MXCK8  = NC_CLK_CK440_MXCK8_DP
  \mxck7#\  = NC_CLK_CK440_MXCK7_DN
  MXCK7  = NC_CLK_CK440_MXCK7_DP
  \mxck6#\  = NC_CLK_CK440_MXCK6_DN
  MXCK6  = NC_CLK_CK440_MXCK6_DP
  \mxck5#\  = NC_CLK_CK440_MXCK5_DN
  MXCK5  = NC_CLK_CK440_MXCK5_DP
  \mxck4#\  = NC_CLK_CK440_MXCK4_DN
  MXCK4  = NC_CLK_CK440_MXCK4_DP
  \mxck3#\  = NC_CLK_CK440_MXCK3_DN
  MXCK3  = NC_CLK_CK440_MXCK3_DP
  \mxck2#\  = CLK_100M_CK440_PCH_EXTCLK_R_DN
  MXCK2  = CLK_100M_CK440_PCH_EXTCLK_R_DP
  \mxck1#\  = NC_CLK_CK440_MXCK1_DN
  MXCK1  = NC_CLK_CK440_MXCK1_DP
  \mxck0#\  = NC_CLK_CK440_MXCK0_DN
  MXCK0  = NC_CLK_CK440_MXCK0_DP
  SBI_OUT  = TP_CK440_SBI_DATA_OUT
  SBI_CLK  = PD_CK440_SBI_CLK
  \25m2#\  = CLK_25M_CK440_ISCLK_REF_DN
  \25m2\  = CLK_25M_CK440_ISCLK_REF_DP
  VDDA25M  = P3V3_AUX_CLK_GEN_VDDA25M_CK440
  NC_B2  = NC_CK440_B2
  NC_B3  = NC_CK440_B3
  \pft_lost#\  = PU_CLK_PFT_LOST_N
  NC_B5  = NC_CK440_B5
  VDDPT  = P3V3_AUX_CLK_GEN_VDDPT_CK440
  NC_B7  = NC_CK440_B7
  SMBDATTA  = SMB_HOST_CLK_3V3AUX_SDA
  SMB_ADR1_TRI  = CLK_CK440_SMB_ADDR1
  GNDS  = GND
  XOUT  = XTAL_CLK_GEN1_25M_X2
  NVGND  = GND
  NC_B13  = NC_CK440_B13
  \oe6#\  = CK440Q_OE_6
  \oe5#\  = CK440Q_OE_5
  NC_B16  = NC_CK440_B16
  VDDA100M  = P3V3_AUX_CLK_GEN_VDDA100M_CK440
  NC_B18  = NC_CK440_B18
  \oe4#\  = CK440Q_OE_4
  NC_B20  = NC_CK440_B20
  VDD100M_B21  = P3V3_AUX_CLK_GEN_VDD_CK440
  NC_B22  = NC_CK440_B22
  VDD100M_B23  = P3V3_AUX_CLK_GEN_VDD_CK440
  NC_B24  = NC_CK440_B24
  NC_B25  = NC_CK440_B25
  NC_B26  = NC_CK440_B26
  \oe0#\  = FM_CLK_GEN1_OE0_N
  NC_B28  = NC_CK440_B28
  VDDMXCK_B29  = P3V3_AUX_CLK_GEN_VDDMXCK_CK440
  NC_B30  = NC_CK440_B30
  NC_B31  = NC_CK440_B31
  VDDMXCK_B32  = P3V3_AUX_CLK_GEN_VDDMXCK_CK440
  NC_B33  = NC_CK440_B33
  NC_B34  = NC_CK440_B34
  VDDMXCK_B35  = P3V3_AUX_CLK_GEN_VDDMXCK_CK440
  NC_B36  = NC_CK440_B36
  NC_B37  = NC_CK440_B37
  \mxck_sel_100m#\  = FM_CK440_MXCK_25M_100M
  NC_B39  = NC_CK440_B39
  VDDMXCK_B40  = P3V3_AUX_CLK_GEN_VDDMXCK_CK440
  NC_B41  = NC_CK440_B41
  \shft_ld#\  = PU_CK440_SHFT_LD_N
  SBI_IN  = PD_CK440_SBI_DATA_IN
  NC_B44  = NC_CK440_B44
  EPAD  = GND

(kicad_pcb
	(version 20260206)
	(generator "pcbnew")
	(generator_version "10.0")
	(general
		(thickness 1.6)
		(legacy_teardrops no)
	)
	(paper "A4")
	(title_block
		(title "03242023_DA0F0TMBIJ0_F0T_Motherboard_J_brd_V01_OCP.brd")
		(comment 1 "Grand Teton / footprint 1793 of 6105 (U13), pads 88-101 of 101")
	)
	(layers
		(0 "F.Cu" signal "TOP")
		(4 "In1.Cu" signal "GND")
		(6 "In2.Cu" signal "IN1")
		(8 "In3.Cu" signal "GND1")
		(10 "In4.Cu" signal "IN2")
		(12 "In5.Cu" signal "GND2")
		(14 "In6.Cu" signal "IN3")
		(16 "In7.Cu" signal "GND3")
		(18 "In8.Cu" signal "VCC")
		(20 "In9.Cu" signal "VCC1")
		(22 "In10.Cu" signal "GND4")
		(24 "In11.Cu" signal "IN4")
		(26 "In12.Cu" signal "GND5")
		(28 "In13.Cu" signal "IN5")
		(30 "In14.Cu" signal "GND6")
		(32 "In15.Cu" signal "IN6")
		(34 "In16.Cu" signal "GND7")
		(2 "B.Cu" signal "BOTTOM")
		(9 "F.Adhes" user "F.Adhesive")
		(11 "B.Adhes" user "B.Adhesive")
		(13 "F.Paste" user "Package Geometry/Pastemask Top")
		(15 "B.Paste" user "Package Geometry/Pastemask Bottom")
		(5 "F.SilkS" user "Ref Des/Silkscreen Top")
		(7 "B.SilkS" user "Ref Des/Silkscreen Bottom")
		(1 "F.Mask" user "Board Geometry/Soldermask Top")
		(3 "B.Mask" user "Board Geometry/Soldermask Bottom")
		(17 "Dwgs.User" user "User.Drawings")
		(19 "Cmts.User" user "User.Comments")
		(21 "Eco1.User" user "User.Eco1")
		(23 "Eco2.User" user "User.Eco2")
		(25 "Edge.Cuts" user "Board Geometry/Outline")
		(27 "Margin" user)
		(31 "F.CrtYd" user "Package Geometry/Place Bound Top")
		(29 "B.CrtYd" user "Package Geometry/Place Bound Bottom")
		(35 "F.Fab" user "Ref Des/Assembly Top")
		(33 "B.Fab" user "Ref Des/Assembly Bottom")
	)
	(footprint ""
		(layer "F.Cu")
		(at 255.68275 -99.563174)
		(property "Reference" "U13"
			(at 3.232404 -8.016748 0)
			(unlocked yes)
			(layer "F.SilkS")
			(effects
				(font
					(size 0.7874 0.5842)
					(thickness 0.1524)
				)
				(justify left)
			)
		)
		(property "Value" ""
			(at 0 0 0)
			(layer "F.Fab")
			(effects
				(font
					(size 1.27 1.27)
				)
			)
		)
		(duplicate_pad_numbers_are_jumpers no)
		(pad "B32" smd rect
			(at 3.124962 -1.999996 270)
			(size 0.2794 0.4572)
			(layers "F.Cu" "F.Mask" "F.Paste")
			(net "P3V3_AUX_CLK_GEN_VDDMXCK_CK440")
		)
		(pad "B33" smd rect
			(at 3.124962 -2.500122 270)
			(size 0.2794 0.4572)
			(layers "F.Cu" "F.Mask" "F.Paste")
			(net "NC_CK440_B33")
		)
		(pad "B34" smd rect
			(at 2.500122 -3.124962)
			(size 0.2794 0.4572)
			(layers "F.Cu" "F.Mask" "F.Paste")
			(net "NC_CK440_B34")
		)
		(pad "B35" smd rect
			(at 1.999996 -3.124962)
			(size 0.2794 0.4572)
			(layers "F.Cu" "F.Mask" "F.Paste")
			(net "P3V3_AUX_CLK_GEN_VDDMXCK_CK440")
		)
		(pad "B36" smd rect
			(at 1.500124 -3.124962)
			(size 0.2794 0.4572)
			(layers "F.Cu" "F.Mask" "F.Paste")
			(net "NC_CK440_B36")
		)
		(pad "B37" smd rect
			(at 0.999998 -3.124962)
			(size 0.2794 0.4572)
			(layers "F.Cu" "F.Mask" "F.Paste")
			(net "NC_CK440_B37")
		)
		(pad "B38" smd rect
			(at 0.499872 -3.124962)
			(size 0.2794 0.4572)
			(layers "F.Cu" "F.Mask" "F.Paste")
			(net "FM_CK440_MXCK_25M_100M")
		)
		(pad "B39" smd rect
			(at 0 -3.124962)
			(size 0.2794 0.4572)
			(layers "F.Cu" "F.Mask" "F.Paste")
			(net "NC_CK440_B39")
		)
		(pad "B40" smd rect
			(at -0.499872 -3.124962)
			(size 0.2794 0.4572)
			(layers "F.Cu" "F.Mask" "F.Paste")
			(net "P3V3_AUX_CLK_GEN_VDDMXCK_CK440")
		)
		(pad "B41" smd rect
			(at -0.999998 -3.124962)
			(size 0.2794 0.4572)
			(layers "F.Cu" "F.Mask" "F.Paste")
			(net "NC_CK440_B41")
		)
		(pad "B42" smd rect
			(at -1.500124 -3.124962)
			(size 0.2794 0.4572)
			(layers "F.Cu" "F.Mask" "F.Paste")
			(net "PU_CK440_SHFT_LD_N")
		)
		(pad "B43" smd rect
			(at -1.999996 -3.124962)
			(size 0.2794 0.4572)
			(layers "F.Cu" "F.Mask" "F.Paste")
			(net "PD_CK440_SBI_DATA_IN")
		)
		(pad "B44" smd rect
			(at -2.500122 -3.124962)
			(size 0.2794 0.4572)
			(layers "F.Cu" "F.Mask" "F.Paste")
			(net "NC_CK440_B44")
		)
		(pad "C1" smd circle
			(at 0 0)
			(size 0 0)
			(layers "F.Cu" "F.Mask" "F.Paste")
			(net "GND")
		)
	)
)
